(kicad_pcb
	(version 20241229)
	(generator "pcbnew")
	(generator_version "9.0")
	(general
		(thickness 1.552)
		(legacy_teardrops no)
	)
	(paper "A4")
	(title_block
		(date "2023-07-25")
		(rev "1.1.4")
		(comment 9 "footprints 294-298 of 379")
	)
	(layers
		(0 "F.Cu" signal)
		(4 "In1.Cu" signal)
		(6 "In2.Cu" signal)
		(8 "In3.Cu" signal)
		(10 "In4.Cu" signal)
		(12 "In5.Cu" signal)
		(14 "In6.Cu" signal)
		(2 "B.Cu" signal)
		(9 "F.Adhes" user "F.Adhesive")
		(11 "B.Adhes" user "B.Adhesive")
		(13 "F.Paste" user)
		(15 "B.Paste" user)
		(5 "F.SilkS" user "F.Silkscreen")
		(7 "B.SilkS" user "B.Silkscreen")
		(1 "F.Mask" user)
		(3 "B.Mask" user)
		(17 "Dwgs.User" user "User.Drawings")
		(19 "Cmts.User" user "User.Comments")
		(21 "Eco1.User" user "User.Eco1")
		(23 "Eco2.User" user "User.Eco2")
		(25 "Edge.Cuts" user)
		(27 "Margin" user)
		(31 "F.CrtYd" user "F.Courtyard")
		(29 "B.CrtYd" user "B.Courtyard")
		(35 "F.Fab" user)
		(33 "B.Fab" user)
	)
	(footprint "antmicro-footprints:R_Array_4x0402"
		(layer "B.Cu")
		(at 123.96 60.33 90)
		(property "Reference" "R46"
			(at -1.01 1.87 90)
			(layer "B.SilkS")
			(effects
				(font
					(size 0.65 0.65)
					(thickness 0.15)
				)
				(justify right bottom mirror)
			)
		)
		(property "Value" "R_4x51R_0402_array"
			(at -1.5 -2 90)
			(layer "B.Fab")
			(hide yes)
			(effects
				(font
					(size 0.7 0.7)
					(thickness 0.15)
				)
				(justify right bottom mirror)
			)
		)
		(property "Datasheet" "http://industrial.panasonic.com/cdbs/www-data/pdf/AOC0000/AOC0000C14.pdf"
			(at 0 0 90)
			(layer "F.Fab")
			(hide yes)
			(effects
				(font
					(size 1.27 1.27)
					(thickness 0.15)
				)
			)
		)
		(property "Description" "Fixed Network Resistor, 51 ohm, Isolated, 4 Resistors, 0804 [2010 Metric], Convex, ± 5%"
			(at 0 0 90)
			(layer "F.Fab")
			(hide yes)
			(effects
				(font
					(size 1.27 1.27)
					(thickness 0.15)
				)
			)
		)
		(property "Author" "Antmicro"
			(at 184.29 -63.63 0)
			(layer "B.Fab")
			(hide yes)
			(effects
				(font
					(size 1 1)
					(thickness 0.15)
				)
				(justify mirror)
			)
		)
		(property "License" "Apache-2.0"
			(at 184.29 -63.63 0)
			(layer "B.Fab")
			(hide yes)
			(effects
				(font
					(size 1 1)
					(thickness 0.15)
				)
				(justify mirror)
			)
		)
		(property "MPN" "EXB28V510JX"
			(at 184.29 -63.63 0)
			(layer "B.Fab")
			(hide yes)
			(effects
				(font
					(size 1 1)
					(thickness 0.15)
				)
				(justify mirror)
			)
		)
		(property "Manufacturer" "Panasonic"
			(at 184.29 -63.63 0)
			(layer "B.Fab")
			(hide yes)
			(effects
				(font
					(size 1 1)
					(thickness 0.15)
				)
				(justify mirror)
			)
		)
		(property "Val" "R_4x51R_0402"
			(at 184.29 -63.63 0)
			(layer "B.Fab")
			(hide yes)
			(effects
				(font
					(size 1 1)
					(thickness 0.15)
				)
				(justify mirror)
			)
		)
		(sheetname "/DDR3/")
		(sheetfile "ddr3.kicad_sch")
		(attr smd)
		(fp_line
			(start 1.167 -0.498)
			(end 1.167 0.5)
			(stroke
				(width 0.15)
				(type solid)
			)
			(layer "B.SilkS")
		)
		(fp_line
			(start -1.17 0.5)
			(end -1.17 -0.498)
			(stroke
				(width 0.15)
				(type solid)
			)
			(layer "B.SilkS")
		)
		(fp_rect
			(start -1.2 0.9)
			(end 1.2 -0.9)
			(stroke
				(width 0.05)
				(type solid)
			)
			(fill no)
			(layer "B.CrtYd")
		)
		(fp_line
			(start 0.998 -0.498)
			(end -1 -0.498)
			(stroke
				(width 0.15)
				(type solid)
			)
			(layer "B.Fab")
		)
		(fp_line
			(start -1 -0.498)
			(end -1 0.5)
			(stroke
				(width 0.15)
				(type solid)
			)
			(layer "B.Fab")
		)
		(fp_line
			(start 0.998 0.5)
			(end 0.998 -0.498)
			(stroke
				(width 0.15)
				(type solid)
			)
			(layer "B.Fab")
		)
		(fp_line
			(start -1 0.5)
			(end 0.998 0.5)
			(stroke
				(width 0.15)
				(type solid)
			)
			(layer "B.Fab")
		)
		(pad "1" smd roundrect
			(at -0.802 -0.45 90)
			(size 0.4 0.5)
			(layers "B.Cu" "B.Mask" "B.Paste")
			(roundrect_rratio 0.25)
			(net 152 "/DDR3/DDR3_A10")
			(pinfunction "R1.1")
			(pintype "passive")
		)
		(pad "2" smd roundrect
			(at -0.272 -0.45 90)
			(size 0.4 0.5)
			(layers "B.Cu" "B.Mask" "B.Paste")
			(roundrect_rratio 0.25)
			(net 160 "/DDR3/DDR3_A12")
			(pinfunction "R2.1")
			(pintype "passive")
		)
		(pad "3" smd roundrect
			(at 0.27 -0.45 90)
			(size 0.4 0.5)
			(layers "B.Cu" "B.Mask" "B.Paste")
			(roundrect_rratio 0.25)
			(net 159 "/DDR3/DDR3_BA1")
			(pinfunction "R3.1")
			(pintype "passive")
		)
		(pad "4" smd roundrect
			(at 0.8 -0.45 90)
			(size 0.4 0.5)
			(layers "B.Cu" "B.Mask" "B.Paste")
			(roundrect_rratio 0.25)
			(net 145 "/DDR3/DDR3_A1")
			(pinfunction "R4.1")
			(pintype "passive")
		)
		(pad "5" smd roundrect
			(at 0.8 0.452 90)
			(size 0.4 0.5)
			(layers "B.Cu" "B.Mask" "B.Paste")
			(roundrect_rratio 0.25)
			(net 6 "Vtt")
			(pinfunction "R4.2")
			(pintype "passive")
		)
		(pad "6" smd roundrect
			(at 0.27 0.452 90)
			(size 0.4 0.5)
			(layers "B.Cu" "B.Mask" "B.Paste")
			(roundrect_rratio 0.25)
			(net 6 "Vtt")
			(pinfunction "R3.2")
			(pintype "passive")
		)
		(pad "7" smd roundrect
			(at -0.272 0.452 90)
			(size 0.4 0.5)
			(layers "B.Cu" "B.Mask" "B.Paste")
			(roundrect_rratio 0.25)
			(net 6 "Vtt")
			(pinfunction "R2.2")
			(pintype "passive")
		)
		(pad "8" smd roundrect
			(at -0.802 0.452 90)
			(size 0.4 0.5)
			(layers "B.Cu" "B.Mask" "B.Paste")
			(roundrect_rratio 0.25)
			(net 6 "Vtt")
			(pinfunction "R1.2")
			(pintype "passive")
		)
	)
	(footprint "antmicro-footprints:TP_SMD_0.75mm"
		(layer "B.Cu")
		(at 92.3892 88.2 90)
		(property "Reference" "TP35"
			(at 0.76 0.39 90)
			(layer "B.SilkS")
			(effects
				(font
					(size 0.65 0.65)
					(thickness 0.15)
				)
				(justify right bottom mirror)
			)
		)
		(property "Value" "TP_0.75mm_SMD"
			(at 0 -1.2 90)
			(layer "B.Fab")
			(hide yes)
			(effects
				(font
					(size 0.7 0.7)
					(thickness 0.15)
				)
				(justify right bottom mirror)
			)
		)
		(property "Description" "SMT test point"
			(at 0 0 90)
			(layer "F.Fab")
			(hide yes)
			(effects
				(font
					(size 1.27 1.27)
					(thickness 0.15)
				)
			)
		)
		(property "Author" "Antmicro"
			(at 180.5892 -4.1892 0)
			(layer "B.Fab")
			(hide yes)
			(effects
				(font
					(size 1 1)
					(thickness 0.15)
				)
				(justify mirror)
			)
		)
		(property "License" "Apache-2.0"
			(at 180.5892 -4.1892 0)
			(layer "B.Fab")
			(hide yes)
			(effects
				(font
					(size 1 1)
					(thickness 0.15)
				)
				(justify mirror)
			)
		)
		(property "MPN" ""
			(at 180.5892 -4.1892 0)
			(layer "B.Fab")
			(hide yes)
			(effects
				(font
					(size 1 1)
					(thickness 0.15)
				)
				(justify mirror)
			)
		)
		(property "Manufacturer" ""
			(at 180.5892 -4.1892 0)
			(layer "B.Fab")
			(hide yes)
			(effects
				(font
					(size 1 1)
					(thickness 0.15)
				)
				(justify mirror)
			)
		)
		(sheetname "/SDI/")
		(sheetfile "sdi.kicad_sch")
		(attr exclude_from_pos_files)
		(fp_circle
			(center 0 0)
			(end 0.475 0)
			(stroke
				(width 0.05)
				(type default)
			)
			(fill no)
			(layer "B.CrtYd")
		)
		(fp_text user "License: Apache-2.0"
			(at -0.4 -5.101 270)
			(layer "B.Fab")
			(effects
				(font
					(size 0.7 0.7)
					(thickness 0.15)
				)
				(justify left bottom mirror)
			)
		)
		(fp_text user "${REFERENCE}"
			(at -0.4 -2.7 270)
			(layer "B.Fab")
			(effects
				(font
					(size 0.7 0.7)
					(thickness 0.15)
				)
				(justify left bottom mirror)
			)
		)
		(fp_text user "Author: Antmicro"
			(at -0.4 -3.901 270)
			(layer "B.Fab")
			(effects
				(font
					(size 0.7 0.7)
					(thickness 0.15)
				)
				(justify left bottom mirror)
			)
		)
		(pad "1" smd circle
			(at 0 0 90)
			(size 0.75 0.75)
			(layers "B.Cu" "B.Mask")
			(net 209 "/SDI/~{RC_BYP}")
			(pinfunction "1")
			(pintype "passive")
		)
	)
	(footprint "antmicro-footprints:C_0402_1005Metric"
		(layer "B.Cu")
		(at 127.97 70.95 -90)
		(descr "Capacitor SMD 0402")
		(tags "capacitor SMD 0402")
		(property "Reference" "C47"
			(at -1.01 0.64 90)
			(layer "B.SilkS")
			(effects
				(font
					(size 0.65 0.65)
					(thickness 0.15)
				)
				(justify left bottom mirror)
			)
		)
		(property "Value" "C_100n_0402"
			(at 0 -1.4 90)
			(layer "B.Fab")
			(hide yes)
			(effects
				(font
					(size 0.7 0.7)
					(thickness 0.15)
				)
				(justify left bottom mirror)
			)
		)
		(property "Datasheet" "https://www.murata.com/products/productdetail?partno=GRM155R61H104KE14%23"
			(at 0 0 270)
			(layer "F.Fab")
			(hide yes)
			(effects
				(font
					(size 1.27 1.27)
					(thickness 0.15)
				)
			)
		)
		(property "Description" "SMD Multilayer Ceramic Capacitor, 0.1 µF, 50 V, 0402 [1005 Metric], ± 10%, X5R, GRM Series"
			(at 0 0 270)
			(layer "F.Fab")
			(hide yes)
			(effects
				(font
					(size 1.27 1.27)
					(thickness 0.15)
				)
			)
		)
		(property "Author" "Antmicro"
			(at 57.02 198.92 0)
			(layer "B.Fab")
			(hide yes)
			(effects
				(font
					(size 1 1)
					(thickness 0.15)
				)
				(justify mirror)
			)
		)
		(property "Dielectric" "X5R"
			(at 57.02 198.92 0)
			(layer "B.Fab")
			(hide yes)
			(effects
				(font
					(size 1 1)
					(thickness 0.15)
				)
				(justify mirror)
			)
		)
		(property "License" "Apache-2.0"
			(at 57.02 198.92 0)
			(layer "B.Fab")
			(hide yes)
			(effects
				(font
					(size 1 1)
					(thickness 0.15)
				)
				(justify mirror)
			)
		)
		(property "MPN" "GRM155R61H104KE14D"
			(at 57.02 198.92 0)
			(layer "B.Fab")
			(hide yes)
			(effects
				(font
					(size 1 1)
					(thickness 0.15)
				)
				(justify mirror)
			)
		)
		(property "Manufacturer" "Murata"
			(at 57.02 198.92 0)
			(layer "B.Fab")
			(hide yes)
			(effects
				(font
					(size 1 1)
					(thickness 0.15)
				)
				(justify mirror)
			)
		)
		(property "Val" "100n"
			(at 57.02 198.92 0)
			(layer "B.Fab")
			(hide yes)
			(effects
				(font
					(size 1 1)
					(thickness 0.15)
				)
				(justify mirror)
			)
		)
		(property "Voltage" "50V"
			(at 57.02 198.92 0)
			(layer "B.Fab")
			(hide yes)
			(effects
				(font
					(size 1 1)
					(thickness 0.15)
				)
				(justify mirror)
			)
		)
		(sheetname "/DDR3/")
		(sheetfile "ddr3.kicad_sch")
		(attr smd)
		(fp_rect
			(start -0.925 0.47)
			(end 0.925 -0.47)
			(stroke
				(width 0.05)
				(type default)
			)
			(fill no)
			(layer "B.CrtYd")
		)
		(fp_line
			(start -0.494 0.25)
			(end 0.504 0.25)
			(stroke
				(width 0.15)
				(type solid)
			)
			(layer "B.Fab")
		)
		(fp_line
			(start 0.504 0.25)
			(end 0.504 -0.248)
			(stroke
				(width 0.15)
				(type solid)
			)
			(layer "B.Fab")
		)
		(fp_line
			(start -0.494 -0.248)
			(end -0.494 0.25)
			(stroke
				(width 0.15)
				(type solid)
			)
			(layer "B.Fab")
		)
		(fp_line
			(start 0.504 -0.248)
			(end -0.494 -0.248)
			(stroke
				(width 0.15)
				(type solid)
			)
			(layer "B.Fab")
		)
		(fp_text user "${REFERENCE}"
			(at -0.939 -4.599 90)
			(layer "B.Fab")
			(effects
				(font
					(size 0.7 0.7)
					(thickness 0.15)
				)
				(justify left bottom mirror)
			)
		)
		(fp_text user "License: Apache-2.0"
			(at -0.939 -5.799 90)
			(layer "B.Fab")
			(effects
				(font
					(size 0.7 0.7)
					(thickness 0.15)
				)
				(justify left bottom mirror)
			)
		)
		(fp_text user "Author: Antmicro"
			(at -0.939 -3.399 90)
			(layer "B.Fab")
			(effects
				(font
					(size 0.7 0.7)
					(thickness 0.15)
				)
				(justify left bottom mirror)
			)
		)
		(pad "1" smd roundrect
			(at -0.48 0 270)
			(size 0.59 0.64)
			(layers "B.Cu" "B.Mask" "B.Paste")
			(roundrect_rratio 0.25)
			(net 1 "GND")
			(pintype "passive")
		)
		(pad "2" smd roundrect
			(at 0.48 0 270)
			(size 0.59 0.64)
			(layers "B.Cu" "B.Mask" "B.Paste")
			(roundrect_rratio 0.25)
			(net 248 "+1V5")
			(pintype "passive")
		)
	)
	(footprint "antmicro-footprints:R_0402_1005Metric"
		(layer "B.Cu")
		(at 161.69 74.9)
		(descr "Resistor SMD 0402")
		(tags "resistor SMD 0402")
		(property "Reference" "R6"
			(at -0.96 0.84 180)
			(layer "B.SilkS")
			(effects
				(font
					(size 0.65 0.65)
					(thickness 0.15)
				)
				(justify left bottom mirror)
			)
		)
		(property "Value" "R_10k_0402"
			(at 0 -1.4 180)
			(layer "B.Fab")
			(hide yes)
			(effects
				(font
					(size 0.7 0.7)
					(thickness 0.15)
				)
				(justify left bottom mirror)
			)
		)
		(property "Datasheet" "https://www.bourns.com/docs/product-datasheets/cr.pdf"
			(at 0 0 0)
			(layer "F.Fab")
			(hide yes)
			(effects
				(font
					(size 1.27 1.27)
					(thickness 0.15)
				)
			)
		)
		(property "Description" "SMD Chip Resistor, 10 kohm, ± 1%, 62.5 mW, 0402 [1005 Metric], Thick Film, General Purpose"
			(at 0 0 0)
			(layer "F.Fab")
			(hide yes)
			(effects
				(font
					(size 1.27 1.27)
					(thickness 0.15)
				)
			)
		)
		(property "Author" "Antmicro"
			(at 0 0 0)
			(layer "B.Fab")
			(hide yes)
			(effects
				(font
					(size 1 1)
					(thickness 0.15)
				)
				(justify mirror)
			)
		)
		(property "License" "Apache-2.0"
			(at 0 0 0)
			(layer "B.Fab")
			(hide yes)
			(effects
				(font
					(size 1 1)
					(thickness 0.15)
				)
				(justify mirror)
			)
		)
		(property "MPN" "CR0402-FX-1002GLF"
			(at 0 0 0)
			(layer "B.Fab")
			(hide yes)
			(effects
				(font
					(size 1 1)
					(thickness 0.15)
				)
				(justify mirror)
			)
		)
		(property "Manufacturer" "Bourns"
			(at 0 0 0)
			(layer "B.Fab")
			(hide yes)
			(effects
				(font
					(size 1 1)
					(thickness 0.15)
				)
				(justify mirror)
			)
		)
		(property "Tolerance" "1%"
			(at 0 0 0)
			(layer "B.Fab")
			(hide yes)
			(effects
				(font
					(size 1 1)
					(thickness 0.15)
				)
				(justify mirror)
			)
		)
		(property "Val" "10k"
			(at 0 0 0)
			(layer "B.Fab")
			(hide yes)
			(effects
				(font
					(size 1 1)
					(thickness 0.15)
				)
				(justify mirror)
			)
		)
		(sheetname "/Power Supply/")
		(sheetfile "supply.kicad_sch")
		(attr smd)
		(fp_rect
			(start -0.925 0.47)
			(end 0.925 -0.47)
			(stroke
				(width 0.05)
				(type default)
			)
			(fill no)
			(layer "B.CrtYd")
		)
		(fp_rect
			(start -0.5 0.25)
			(end 0.5 -0.25)
			(stroke
				(width 0.15)
				(type solid)
			)
			(fill no)
			(layer "B.Fab")
		)
		(fp_text user "License: Apache-2.0"
			(at -0.95 -5.169 180)
			(layer "B.Fab")
			(effects
				(font
					(size 0.7 0.7)
					(thickness 0.15)
				)
				(justify left bottom mirror)
			)
		)
		(fp_text user "Author: Antmicro"
			(at -0.95 -4.169 180)
			(layer "B.Fab")
			(effects
				(font
					(size 0.7 0.7)
					(thickness 0.15)
				)
				(justify left bottom mirror)
			)
		)
		(fp_text user "${REFERENCE}"
			(at -0.95 -3.168 180)
			(layer "B.Fab")
			(effects
				(font
					(size 0.7 0.7)
					(thickness 0.15)
				)
				(justify left bottom mirror)
			)
		)
		(pad "1" smd roundrect
			(at -0.48 0)
			(size 0.59 0.64)
			(layers "B.Cu" "B.Mask" "B.Paste")
			(roundrect_rratio 0.25)
			(net 305 "/Power Supply/~{FAULT}")
			(pintype "passive")
		)
		(pad "2" smd roundrect
			(at 0.48 0)
			(size 0.59 0.64)
			(layers "B.Cu" "B.Mask" "B.Paste")
			(roundrect_rratio 0.25)
			(net 329 "/Power Supply/FFC2_5V_1")
			(pintype "passive")
		)
	)
	(footprint "antmicro-footprints:C_0201"
		(layer "B.Cu")
		(at 123.5 92.3 -135)
		(descr "Capacitor SMD 0201")
		(tags "capacitor SMD 0201")
		(property "Reference" "C84"
			(at -3.174909 15.153298 45)
			(layer "B.SilkS")
			(effects
				(font
					(size 0.65 0.65)
					(thickness 0.15)
				)
				(justify left bottom mirror)
			)
		)
		(property "Value" "C_100n_0201"
			(at 0 -1.399999 45)
			(layer "B.Fab")
			(hide yes)
			(effects
				(font
					(size 0.7 0.7)
					(thickness 0.15)
				)
				(justify left bottom mirror)
			)
		)
		(property "Datasheet" "https://www.yageo.com/en/Chart/Download/pdf/CC0201KRX6S5BB104"
			(at 0 0 225)
			(layer "F.Fab")
			(hide yes)
			(effects
				(font
					(size 1.27 1.27)
					(thickness 0.15)
				)
			)
		)
		(property "Description" "SMD Multilayer Ceramic Capacitor, 0.1 µF, 6.3 V, 0201 [0603 Metric], ± 10%, X6S, CC Series"
			(at 0 0 225)
			(layer "F.Fab")
			(hide yes)
			(effects
				(font
					(size 1.27 1.27)
					(thickness 0.15)
				)
			)
		)
		(property "Author" "Antmicro"
			(at 145.561732 244.893643 0)
			(layer "B.Fab")
			(hide yes)
			(effects
				(font
					(size 1 1)
					(thickness 0.15)
				)
				(justify mirror)
			)
		)
		(property "Dielectric" ""
			(at 145.561732 244.893643 0)
			(layer "B.Fab")
			(hide yes)
			(effects
				(font
					(size 1 1)
					(thickness 0.15)
				)
				(justify mirror)
			)
		)
		(property "License" "Apache-2.0"
			(at 145.561732 244.893643 0)
			(layer "B.Fab")
			(hide yes)
			(effects
				(font
					(size 1 1)
					(thickness 0.15)
				)
				(justify mirror)
			)
		)
		(property "MPN" "CC0201KRX6S5BB104"
			(at 145.561732 244.893643 0)
			(layer "B.Fab")
			(hide yes)
			(effects
				(font
					(size 1 1)
					(thickness 0.15)
				)
				(justify mirror)
			)
		)
		(property "Manufacturer" "YAGEO"
			(at 145.561732 244.893643 0)
			(layer "B.Fab")
			(hide yes)
			(effects
				(font
					(size 1 1)
					(thickness 0.15)
				)
				(justify mirror)
			)
		)
		(property "Val" "100n"
			(at 145.561732 244.893643 0)
			(layer "B.Fab")
			(hide yes)
			(effects
				(font
					(size 1 1)
					(thickness 0.15)
				)
				(justify mirror)
			)
		)
		(property "Voltage" ""
			(at 145.561732 244.893643 0)
			(layer "B.Fab")
			(hide yes)
			(effects
				(font
					(size 1 1)
					(thickness 0.15)
				)
				(justify mirror)
			)
		)
		(property "Public" "False"
			(at 0 0 225)
			(unlocked yes)
			(layer "B.Fab")
			(hide yes)
			(effects
				(font
					(size 1 1)
					(thickness 0.15)
				)
				(justify mirror)
			)
		)
		(sheetname "/Peripherals/")
		(sheetfile "peripherals.kicad_sch")
		(attr smd)
		(fp_poly
			(pts
				(xy -0.7 0.35) (xy 0.7 0.35) (xy 0.7 -0.35) (xy -0.7 -0.35)
			)
			(stroke
				(width 0.05)
				(type default)
			)
			(fill no)
			(layer "B.CrtYd")
		)
		(fp_poly
			(pts
				(xy 0.3 -0.15) (xy -0.301 -0.15) (xy -0.301 0.149) (xy 0.3 0.149)
			)
			(stroke
				(width 0.15)
				(type solid)
			)
			(fill no)
			(layer "B.Fab")
		)
		(fp_text user "${REFERENCE}"
			(at -0.72 -3.4 45)
			(layer "B.Fab")
			(effects
				(font
					(size 0.7 0.7)
					(thickness 0.15)
				)
				(justify left bottom mirror)
			)
		)
		(fp_text user "License: Apache-2.0"
			(at -0.72 -4.4 45)
			(layer "B.Fab")
			(effects
				(font
					(size 0.7 0.7)
					(thickness 0.15)
				)
				(justify left bottom mirror)
			)
		)
		(fp_text user "Author: Antmicro"
			(at -0.72 -5.400001 45)
			(layer "B.Fab")
			(effects
				(font
					(size 0.7 0.7)
					(thickness 0.15)
				)
				(justify left bottom mirror)
			)
		)
		(pad "" smd roundrect
			(at -0.349 0.002 225)
			(size 0.318 0.36)
			(layers "B.Paste")
			(roundrect_rratio 0.25)
		)
		(pad "" smd roundrect
			(at 0.341 0.002 225)
			(size 0.318 0.36)
			(layers "B.Paste")
			(roundrect_rratio 0.25)
		)
		(pad "1" smd roundrect
			(at -0.321 0.002 225)
			(size 0.46 0.4)
			(layers "B.Cu" "B.Mask")
			(roundrect_rratio 0.25)
			(net 1 "GND")
			(pintype "passive")
		)
		(pad "2" smd roundrect
			(at 0.32 0.002 225)
			(size 0.46 0.4)
			(layers "B.Cu" "B.Mask")
			(roundrect_rratio 0.25)
			(net 2 "+3V3")
			(pintype "passive")
		)
	)
)
